FILE_TYPE = CONNECTIVITY;
{Allegro Design Entry HDL 16.6-p007 (v16-6-112F) 10/10/2012}
"PAGE_NUMBER" = 246;
0"NC";
1"GND\g";
2"GND\g";
3"P3V3_STBY\g";
4"GND\g";
5"PU_TPM_SPI_BMC_WP_N";
6"SPI_BMC_BT_DI";
7"SPI_BMC_BT_DO";
8"SPI_BMC_BT_CLK";
9"SPI_BMC_CS0_N";
10"TP_TPM_SPI_6";
11"TP_TPM_SPI_5";
12"TP_TPM_SPI_3";
13"TP_TPM_SPI_2";
14"TP_TPM_SPI_4";
15"TP_TPM_SPI_1";
16"TP_TPM_SPI_0";
17"SPI_TPM_BMC_DI_R_";
18"PU_TPM_SPI_BMC_HOLD_N";
19"PU_TPM_SPI_FLASH_RESET_2_N";
%"RES"
"2","(-6275,3150)","2","mstr_discrete","I10";
;
CDS_LOCATION"RN8F2"
ROOM"BMC_BOOT_SPI"
BOM_COST"SM_MEM"
CDS_SEC"1"
$SEC"1"
CDS_LIB"mstr_discrete"
LOCATION"RN8F2"
PACK_TYPE"0402"
PART_NUMBER"G21796-072"
WATTAGE"1/16W"
TOLERANCE"1%"
MATERIAL"CHIP"
VALUE"4.75K";
"A"
$PN"1"3;
"B"
$PN"2"5;
%"RES"
"2","(-6000,3175)","2","mstr_discrete","I11";
;
CDS_LOCATION"RN8F3"
CDS_SEC"1"
CDS_LIB"mstr_discrete"
BOM_COST"SM_MEM"
SEC_TYPE"0402"
ROOM"BMC_BOOT_SPI"
SEC"1"
PACK_TYPE"0402"
WATTAGE"1/16W"
TOLERANCE"1%"
MATERIAL"CHIP"
VALUE"4.75K"
LOCATION"RN8F3"
PART_NUMBER"G21796-072";
"A"
$PN"1"3;
"B"
$PN"2"18;
%"RES"
"2","(-5425,3150)","2","mstr_discrete","I12";
;
CDS_LOCATION"RN8F4"
SEC"1"
ROOM"BMC_BOOT_SPI"
SEC_TYPE"0402"
BOM_COST"SM_MEM"
CDS_LIB"mstr_discrete"
CDS_SEC"1"
PACK_TYPE"0402"
TOLERANCE"1%"
WATTAGE"1/16W"
VALUE"4.75K"
MATERIAL"EMPTY"
PART_NUMBER"G21796-072"
LOCATION"RN8F4";
"A"
$PN"1"3;
"B"
$PN"2"19;
%"GND"
"1","(-3550,2275)","0","mstr_symbols","I13";
;
CDS_LIB"mstr_symbols"
SIZE"1B"
VOLTAGE"0"
BODY_TYPE"PLUMBING"
HDL_POWER"GND";
"A\NAC"1;
%"GND"
"1","(-3225,2925)","0","mstr_symbols","I14";
;
SIZE"1B"
CDS_LIB"mstr_symbols"
VOLTAGE"0.0V"
BODY_TYPE"PLUMBING"
HDL_POWER"GND";
"A\NAC"2;
%"CAP"
"1","(-3525,3250)","0","mstr_discrete","I15";
;
CDS_LOCATION"CN8F1"
CDS_SEC"1"
$SEC"1"
ROOM"BMC_BOOT_SPI"
BOM_COST"SM_MEM"
CDS_LIB"mstr_discrete"
PACK_TYPE"0402"
VOLTAGE"6.3V"
VALUE"1.0UF"
PART_NUMBER"D97712-004"
MATERIAL"X6S"
TOLERANCE"10%"
LOCATION"CN8F1";
"A"
$PN"1"3;
"B"
$PN"2"2;
%"CAP"
"1","(-3225,3250)","0","mstr_discrete","I16";
;
CDS_LOCATION"CN8F2"
ROOM"BMC_BOOT_SPI"
BOM_COST"SM_MEM"
CDS_SEC"1"
$SEC"1"
CDS_LIB"mstr_discrete"
MATERIAL"X7R"
TOLERANCE"10%"
VOLTAGE"25V"
VALUE"0.01UF"
PART_NUMBER"A36096-045"
PACK_TYPE"0402LF"
LOCATION"CN8F2";
"A"
$PN"1"3;
"B"
$PN"2"2;
%"W25Q256"
"1","(-4200,2725)","0","mstr_memory","I17";
;
SEC"1"
BOM_COST"SM_MEM"
SEC_TYPE"XSOI"
ROOM"BMC_BOOT_SPI"
PACK_TYPE"XSOI"
CDS_LIB"mstr_memory"
CDS_LOCATION"UN8F2"
CDS_SEC"1"
PART_NUMBER"H25002-001"
MATERIAL"IC"
LOCATION"UN8F2";
"HOLD_N_IO<3>"
$PN"1"18;
"RESET_N"
$PN"3"19;
"DI_IO<0>"
$PN"15"7;
"CS_N"
$PN"7"9;
"VCC"
$PN"2"3;
"CLK"
$PN"16"8;
"DO_IO<1>"
$PN"8"17;
"GND"
$PN"10"1;
"NC<6>"
$PN"4"10;
"NC<5>"
$PN"5"11;
"NC<4>"
$PN"6"14;
"NC<3>"
$PN"11"12;
"NC<2>"
$PN"12"13;
"NC<1>"
$PN"13"15;
"NC<0>"
$PN"14"16;
"WP_N_IO<2>"
$PN"9"5;
%"RES"
"2","(-6600,3175)","2","mstr_discrete","I5";
;
CDS_LOCATION"RN8F1"
CDS_LIB"mstr_discrete"
BOM_COST"SM_MEM"
ROOM"BMC_BOOT_SPI"
$SEC"1"
CDS_SEC"1"
PACK_TYPE"0402"
VALUE"4.75K"
MATERIAL"CHIP"
TOLERANCE"1%"
WATTAGE"1/16W"
PART_NUMBER"G21796-072"
LOCATION"RN8F1";
"A"
$PN"1"3;
"B"
$PN"2"9;
%"P3V3_STBY"
"1","(-6000,3575)","0","mstr_symbols","I6";
;
SIZE"1B"
CDS_LIB"mstr_symbols"
VOLTAGE"3.3V"
BODY_TYPE"PLUMBING"
HDL_POWER"P3V3_STBY";
"G\NAC"3;
%"GND"
"1","(-6275,1900)","0","mstr_symbols","I7";
;
SIZE"1B"
CDS_LIB"mstr_symbols"
VOLTAGE"0.0V"
BODY_TYPE"PLUMBING"
HDL_POWER"GND";
"A\NAC"4;
%"RES"
"2","(-6275,2225)","0","mstr_discrete","I8";
;
CDS_LOCATION"RN8F6"
CDS_SEC"1"
$SEC"1"
ROOM"BMC_BOOT_SPI"
BOM_COST"SM_MEM"
CDS_LIB"mstr_discrete"
VALUE"1.00K"
TOLERANCE"1%"
WATTAGE"1/16W"
PART_NUMBER"G21796-026"
MATERIAL"EMPTY"
LOCATION"RN8F6"
PACK_TYPE"0402";
"A"
$PN"1"5;
"B"
$PN"2"4;
%"RES"
"1","(-5850,2725)","0","mstr_discrete","I9";
;
CDS_LOCATION"RN8F5"
SEC"1"
SEC_TYPE"0402"
PART_NUMBER"G21796-074"
BOM_COST"SM_MEM"
PACK_TYPE"0402"
MATERIAL"CHIP"
ROOM"BMC_BOOT_SPI"
CDS_LIB"mstr_discrete"
TOLERANCE"1%"
WATTAGE"1/16W"
CDS_SEC"1"
LOCATION"RN8F5"
VALUE"33.2";
"B"
$PN"2"17;
"A"
$PN"1"6;
END.
